(kicad_pcb
	(version 20260206)
	(generator "pcbnew")
	(generator_version "10.0")
	(general
		(thickness 1.6)
		(legacy_teardrops no)
	)
	(paper "A4")
	(title_block
		(title "Bryce Canyon_R.DPB_16317-1_OCP.brd")
		(comment 1 "Bryce Canyon / footprints 1389-1396 of 2099")
	)
	(layers
		(0 "F.Cu" signal "TOP")
		(4 "In1.Cu" signal "L2GND")
		(6 "In2.Cu" signal "L3")
		(8 "In3.Cu" signal "L4VCC")
		(10 "In4.Cu" signal "L5VCC")
		(12 "In5.Cu" signal "L6")
		(14 "In6.Cu" signal "L7GND")
		(2 "B.Cu" signal "BOTTOM")
		(9 "F.Adhes" user "F.Adhesive")
		(11 "B.Adhes" user "B.Adhesive")
		(13 "F.Paste" user "Package Geometry/Pastemask Top")
		(15 "B.Paste" user "Package Geometry/Pastemask Bottom")
		(5 "F.SilkS" user "Ref Des/Silkscreen Top")
		(7 "B.SilkS" user "Ref Des/Silkscreen Bottom")
		(1 "F.Mask" user "Board Geometry/Soldermask Top")
		(3 "B.Mask" user "Board Geometry/Soldermask Bottom")
		(17 "Dwgs.User" user "User.Drawings")
		(19 "Cmts.User" user "User.Comments")
		(21 "Eco1.User" user "User.Eco1")
		(23 "Eco2.User" user "User.Eco2")
		(25 "Edge.Cuts" user "Board Geometry/Outline")
		(27 "Margin" user)
		(31 "F.CrtYd" user "Package Geometry/Place Bound Top")
		(29 "B.CrtYd" user "Package Geometry/Place Bound Bottom")
		(35 "F.Fab" user "Ref Des/Assembly Top")
		(33 "B.Fab" user "Ref Des/Assembly Bottom")
	)
	(footprint ""
		(layer "F.Cu")
		(at 86.106 -134.493 90)
		(property "Reference" "R404"
			(at 0 0 90)
			(layer "F.SilkS")
			(hide yes)
			(effects
				(font
					(size 1.27 1.27)
				)
			)
		)
		(property "Value" "4K7R2F-GP"
			(at 0.064008 -3.993896 90)
			(unlocked yes)
			(layer "F.Fab")
			(hide yes)
			(effects
				(font
					(size 1.016 1.016)
					(thickness 0.1524)
				)
			)
		)
		(property "Device Type" "R402H16"
			(at 0.064008 -5.517896 90)
			(unlocked yes)
			(layer "F.Fab")
			(hide yes)
			(effects
				(font
					(size 1.016 1.016)
					(thickness 0.1524)
				)
			)
		)
		(duplicate_pad_numbers_are_jumpers no)
		(fp_line
			(start 0.508 -0.9398)
			(end -0.508 -0.9398)
			(stroke
				(width 0.1524)
				(type default)
			)
			(layer "F.SilkS")
		)
		(fp_line
			(start -0.508 -0.9398)
			(end -0.508 0.9398)
			(stroke
				(width 0.1524)
				(type default)
			)
			(layer "F.SilkS")
		)
		(fp_rect
			(start -0.508 0.9398)
			(end 0.508 -0.9398)
			(stroke
				(width 0)
				(type default)
			)
			(fill no)
			(layer "F.CrtYd")
		)
		(fp_rect
			(start -0.508 0.9398)
			(end 0.508 -0.9398)
			(stroke
				(width 0)
				(type default)
			)
			(fill no)
			(layer "F.Fab")
		)
		(pad "1" smd custom
			(at 0 -0.4445 90)
			(size 0.1397 0.1397)
			(layers "F.Cu" "F.Mask" "F.Paste")
			(net "SW_PWR_R_HDD14")
			(options
				(clearance outline)
				(anchor circle)
			)
			(primitives
				(gr_poly
					(pts
						(arc
							(start -0.1778 -0.2794)
							(mid -0.249642 -0.249642)
							(end -0.2794 -0.1778)
						)
						(arc
							(start -0.2794 0.1778)
							(mid -0.249642 0.249642)
							(end -0.1778 0.2794)
						)
						(arc
							(start 0.1778 0.2794)
							(mid 0.249642 0.249642)
							(end 0.2794 0.1778)
						)
						(arc
							(start 0.2794 -0.1778)
							(mid 0.249642 -0.249642)
							(end 0.1778 -0.2794)
						)
					)
					(width 0)
					(fill yes)
				)
			)
		)
		(pad "2" smd custom
			(at 0 0.4445 90)
			(size 0.1397 0.1397)
			(layers "F.Cu" "F.Mask" "F.Paste")
			(net "GND")
			(options
				(clearance outline)
				(anchor circle)
			)
			(primitives
				(gr_poly
					(pts
						(arc
							(start -0.1778 -0.2794)
							(mid -0.249642 -0.249642)
							(end -0.2794 -0.1778)
						)
						(arc
							(start -0.2794 0.1778)
							(mid -0.249642 0.249642)
							(end -0.1778 0.2794)
						)
						(arc
							(start 0.1778 0.2794)
							(mid 0.249642 0.249642)
							(end 0.2794 0.1778)
						)
						(arc
							(start 0.2794 -0.1778)
							(mid 0.249642 -0.249642)
							(end 0.1778 -0.2794)
						)
					)
					(width 0)
					(fill yes)
				)
			)
		)
	)
	(footprint ""
		(layer "F.Cu")
		(at 113.538 -35.687 90)
		(property "Reference" "R692"
			(at 0 0 90)
			(layer "F.SilkS")
			(hide yes)
			(effects
				(font
					(size 1.27 1.27)
				)
			)
		)
		(property "Value" "2R6F-GP"
			(at -0.0508 -4.8514 90)
			(unlocked yes)
			(layer "F.Fab")
			(hide yes)
			(effects
				(font
					(size 1.016 1.016)
					(thickness 0.1524)
				)
			)
		)
		(property "Device Type" "R1206H26"
			(at 0 -6.3754 90)
			(unlocked yes)
			(layer "F.Fab")
			(hide yes)
			(effects
				(font
					(size 1.016 1.016)
					(thickness 0.1524)
				)
			)
		)
		(duplicate_pad_numbers_are_jumpers no)
		(fp_line
			(start 1.016 -2.2352)
			(end 1.016 2.2352)
			(stroke
				(width 0.1524)
				(type default)
			)
			(layer "F.SilkS")
		)
		(fp_line
			(start -1.016 -2.2352)
			(end 1.016 -2.2352)
			(stroke
				(width 0.1524)
				(type default)
			)
			(layer "F.SilkS")
		)
		(fp_line
			(start 1.016 2.2352)
			(end -1.016 2.2352)
			(stroke
				(width 0.1524)
				(type default)
			)
			(layer "F.SilkS")
		)
		(fp_line
			(start -1.016 2.2352)
			(end -1.016 -2.2352)
			(stroke
				(width 0.1524)
				(type default)
			)
			(layer "F.SilkS")
		)
		(fp_rect
			(start -1.0922 2.3114)
			(end 1.0922 -2.3114)
			(stroke
				(width 0)
				(type default)
			)
			(fill no)
			(layer "F.CrtYd")
		)
		(fp_poly
			(pts
				(xy -1.0922 -2.3114) (xy 1.0922 -2.3114) (xy 1.0922 2.3114) (xy -1.0922 2.3114)
			)
			(stroke
				(width 0)
				(type default)
			)
			(fill no)
			(layer "F.Fab")
		)
		(pad "1" smd rect
			(at 0 -1.397 90)
			(size 1.651 1.27)
			(layers "F.Cu" "F.Mask" "F.Paste")
			(net "P12V_HDD27")
		)
		(pad "2" smd rect
			(at 0 1.397 90)
			(size 1.651 1.27)
			(layers "F.Cu" "F.Mask" "F.Paste")
			(net "12V_PRE_27")
		)
	)
	(footprint ""
		(layer "F.Cu")
		(at 242.697 -311.912)
		(property "Reference" "R1084"
			(at 0 0 0)
			(layer "F.SilkS")
			(hide yes)
			(effects
				(font
					(size 1.27 1.27)
				)
			)
		)
		(property "Value" "4K7R2F-GP"
			(at 0.064008 -3.993896 0)
			(unlocked yes)
			(layer "F.Fab")
			(hide yes)
			(effects
				(font
					(size 1.016 1.016)
					(thickness 0.1524)
				)
			)
		)
		(property "Device Type" "R402H16"
			(at 0.064008 -5.517896 0)
			(unlocked yes)
			(layer "F.Fab")
			(hide yes)
			(effects
				(font
					(size 1.016 1.016)
					(thickness 0.1524)
				)
			)
		)
		(duplicate_pad_numbers_are_jumpers no)
		(fp_line
			(start -0.508 -0.9398)
			(end -0.508 0.9398)
			(stroke
				(width 0.1524)
				(type default)
			)
			(layer "F.SilkS")
		)
		(fp_line
			(start 0.508 -0.9398)
			(end -0.508 -0.9398)
			(stroke
				(width 0.1524)
				(type default)
			)
			(layer "F.SilkS")
		)
		(fp_rect
			(start -0.508 0.9398)
			(end 0.508 -0.9398)
			(stroke
				(width 0)
				(type default)
			)
			(fill no)
			(layer "F.CrtYd")
		)
		(fp_rect
			(start -0.508 0.9398)
			(end 0.508 -0.9398)
			(stroke
				(width 0)
				(type default)
			)
			(fill no)
			(layer "F.Fab")
		)
		(pad "1" smd custom
			(at 0 -0.4445)
			(size 0.1397 0.1397)
			(layers "F.Cu" "F.Mask" "F.Paste")
			(net "P3V3_STBY_A")
			(options
				(clearance outline)
				(anchor circle)
			)
			(primitives
				(gr_poly
					(pts
						(arc
							(start -0.1778 -0.2794)
							(mid -0.249642 -0.249642)
							(end -0.2794 -0.1778)
						)
						(arc
							(start -0.2794 0.1778)
							(mid -0.249642 0.249642)
							(end -0.1778 0.2794)
						)
						(arc
							(start 0.1778 0.2794)
							(mid 0.249642 0.249642)
							(end 0.2794 0.1778)
						)
						(arc
							(start 0.2794 -0.1778)
							(mid 0.249642 -0.249642)
							(end 0.1778 -0.2794)
						)
					)
					(width 0)
					(fill yes)
				)
			)
		)
		(pad "2" smd custom
			(at 0 0.4445)
			(size 0.1397 0.1397)
			(layers "F.Cu" "F.Mask" "F.Paste")
			(net "MAX31790_A_ADD1")
			(options
				(clearance outline)
				(anchor circle)
			)
			(primitives
				(gr_poly
					(pts
						(arc
							(start -0.1778 -0.2794)
							(mid -0.249642 -0.249642)
							(end -0.2794 -0.1778)
						)
						(arc
							(start -0.2794 0.1778)
							(mid -0.249642 0.249642)
							(end -0.1778 0.2794)
						)
						(arc
							(start 0.1778 0.2794)
							(mid 0.249642 0.249642)
							(end 0.2794 0.1778)
						)
						(arc
							(start 0.2794 -0.1778)
							(mid 0.249642 -0.249642)
							(end 0.1778 -0.2794)
						)
					)
					(width 0)
					(fill yes)
				)
			)
		)
	)
	(footprint ""
		(layer "F.Cu")
		(at 160.485582 -244.990874 90)
		(property "Reference" "VIA9"
			(at 0 0 90)
			(layer "F.SilkS")
			(hide yes)
			(effects
				(font
					(size 1.27 1.27)
				)
			)
		)
		(property "Value" "100OHM-8L-2D36MM-L18-GP"
			(at 3.8989 0.5715 90)
			(unlocked yes)
			(layer "F.Fab")
			(hide yes)
			(effects
				(font
					(size 1.016 1.016)
					(thickness 0.1524)
				)
			)
		)
		(property "Device Type" "VIA-PCIE-4P-414097"
			(at 3.8989 -0.9525 90)
			(unlocked yes)
			(layer "F.Fab")
			(hide yes)
			(effects
				(font
					(size 1.016 1.016)
					(thickness 0.1524)
				)
			)
		)
		(duplicate_pad_numbers_are_jumpers no)
		(fp_rect
			(start -2.0701 0.4826)
			(end 2.0701 -0.4826)
			(stroke
				(width 0)
				(type default)
			)
			(fill no)
			(layer "F.CrtYd")
		)
		(fp_rect
			(start -2.0701 0.4826)
			(end 2.0701 -0.4826)
			(stroke
				(width 0)
				(type default)
			)
			(fill no)
			(layer "F.Fab")
		)
		(pad "1" thru_hole circle
			(at -1.5875 0 90)
			(size 0.508 0.508)
			(drill 0.254)
			(layers "*.Cu" "*.Mask")
			(remove_unused_layers no)
			(net "GND")
			(clearance 0.2286)
			(thermal_gap 0.2286)
		)
		(pad "2" thru_hole circle
			(at -0.5715 0 90)
			(size 0.508 0.508)
			(drill 0.254)
			(layers "*.Cu" "*.Mask")
			(remove_unused_layers no)
			(net "PHY_SCC_B_TO_DRV_B_4_DP")
			(clearance 0.2286)
			(thermal_gap 0.2286)
		)
		(pad "3" thru_hole circle
			(at 0.5715 0 90)
			(size 0.508 0.508)
			(drill 0.254)
			(layers "*.Cu" "*.Mask")
			(remove_unused_layers no)
			(net "PHY_SCC_B_TO_DRV_B_4_DN")
			(clearance 0.2286)
			(thermal_gap 0.2286)
		)
		(pad "4" thru_hole circle
			(at 1.5875 0 90)
			(size 0.508 0.508)
			(drill 0.254)
			(layers "*.Cu" "*.Mask")
			(remove_unused_layers no)
			(net "GND")
			(clearance 0.2286)
			(thermal_gap 0.2286)
		)
	)
	(footprint ""
		(layer "F.Cu")
		(at 247.761252 -368.784632 180)
		(property "Reference" "R1024"
			(at 0 0 180)
			(layer "F.SilkS")
			(hide yes)
			(effects
				(font
					(size 1.27 1.27)
				)
			)
		)
		(property "Value" "100R2D-GP"
			(at 0.064008 -3.993896 180)
			(unlocked yes)
			(layer "F.Fab")
			(hide yes)
			(effects
				(font
					(size 1.016 1.016)
					(thickness 0.1524)
				)
			)
		)
		(property "Device Type" "R402H14"
			(at 0.064008 -5.517896 180)
			(unlocked yes)
			(layer "F.Fab")
			(hide yes)
			(effects
				(font
					(size 1.016 1.016)
					(thickness 0.1524)
				)
			)
		)
		(duplicate_pad_numbers_are_jumpers no)
		(fp_line
			(start 0.508 -0.9398)
			(end -0.508 -0.9398)
			(stroke
				(width 0.1524)
				(type default)
			)
			(layer "F.SilkS")
		)
		(fp_line
			(start -0.508 -0.9398)
			(end -0.508 0.9398)
			(stroke
				(width 0.1524)
				(type default)
			)
			(layer "F.SilkS")
		)
		(fp_rect
			(start -0.508 0.9398)
			(end 0.508 -0.9398)
			(stroke
				(width 0)
				(type default)
			)
			(fill no)
			(layer "F.CrtYd")
		)
		(fp_rect
			(start -0.508 0.9398)
			(end 0.508 -0.9398)
			(stroke
				(width 0)
				(type default)
			)
			(fill no)
			(layer "F.Fab")
		)
		(pad "1" smd custom
			(at 0 -0.4445 180)
			(size 0.1397 0.1397)
			(layers "F.Cu" "F.Mask" "F.Paste")
			(net "MB3_TEMP")
			(options
				(clearance outline)
				(anchor circle)
			)
			(primitives
				(gr_poly
					(pts
						(arc
							(start -0.1778 -0.2794)
							(mid -0.249642 -0.249642)
							(end -0.2794 -0.1778)
						)
						(arc
							(start -0.2794 0.1778)
							(mid -0.249642 0.249642)
							(end -0.1778 0.2794)
						)
						(arc
							(start 0.1778 0.2794)
							(mid 0.249642 0.249642)
							(end 0.2794 0.1778)
						)
						(arc
							(start 0.2794 -0.1778)
							(mid 0.249642 -0.249642)
							(end 0.1778 -0.2794)
						)
					)
					(width 0)
					(fill yes)
				)
			)
		)
		(pad "2" smd custom
			(at 0 0.4445 180)
			(size 0.1397 0.1397)
			(layers "F.Cu" "F.Mask" "F.Paste")
			(net "MB3_TEMP_B")
			(options
				(clearance outline)
				(anchor circle)
			)
			(primitives
				(gr_poly
					(pts
						(arc
							(start -0.1778 -0.2794)
							(mid -0.249642 -0.249642)
							(end -0.2794 -0.1778)
						)
						(arc
							(start -0.2794 0.1778)
							(mid -0.249642 0.249642)
							(end -0.1778 0.2794)
						)
						(arc
							(start 0.1778 0.2794)
							(mid 0.249642 0.249642)
							(end 0.2794 0.1778)
						)
						(arc
							(start 0.2794 -0.1778)
							(mid 0.249642 -0.249642)
							(end 0.1778 -0.2794)
						)
					)
					(width 0)
					(fill yes)
				)
			)
		)
	)
	(footprint ""
		(layer "F.Cu")
		(at 209.423 -204.978 -90)
		(property "Reference" "R48"
			(at 0 0 270)
			(layer "F.SilkS")
			(hide yes)
			(effects
				(font
					(size 1.27 1.27)
				)
			)
		)
		(property "Value" "0R2J-2-GP"
			(at 0.064008 -3.993896 270)
			(unlocked yes)
			(layer "F.Fab")
			(hide yes)
			(effects
				(font
					(size 1.016 1.016)
					(thickness 0.1524)
				)
			)
		)
		(property "Device Type" "R402H16"
			(at 0.064008 -5.517896 270)
			(unlocked yes)
			(layer "F.Fab")
			(hide yes)
			(effects
				(font
					(size 1.016 1.016)
					(thickness 0.1524)
				)
			)
		)
		(duplicate_pad_numbers_are_jumpers no)
		(fp_line
			(start -0.508 -0.9398)
			(end -0.508 0.9398)
			(stroke
				(width 0.1524)
				(type default)
			)
			(layer "F.SilkS")
		)
		(fp_line
			(start 0.508 -0.9398)
			(end -0.508 -0.9398)
			(stroke
				(width 0.1524)
				(type default)
			)
			(layer "F.SilkS")
		)
		(fp_rect
			(start -0.508 0.9398)
			(end 0.508 -0.9398)
			(stroke
				(width 0)
				(type default)
			)
			(fill no)
			(layer "F.CrtYd")
		)
		(fp_rect
			(start -0.508 0.9398)
			(end 0.508 -0.9398)
			(stroke
				(width 0)
				(type default)
			)
			(fill no)
			(layer "F.Fab")
		)
		(pad "1" smd custom
			(at 0 -0.4445 270)
			(size 0.1397 0.1397)
			(layers "F.Cu" "F.Mask" "F.Paste")
			(net "IO_EXP5_SDA")
			(options
				(clearance outline)
				(anchor circle)
			)
			(primitives
				(gr_poly
					(pts
						(arc
							(start -0.1778 -0.2794)
							(mid -0.249642 -0.249642)
							(end -0.2794 -0.1778)
						)
						(arc
							(start -0.2794 0.1778)
							(mid -0.249642 0.249642)
							(end -0.1778 0.2794)
						)
						(arc
							(start 0.1778 0.2794)
							(mid 0.249642 0.249642)
							(end 0.2794 0.1778)
						)
						(arc
							(start 0.2794 -0.1778)
							(mid 0.249642 -0.249642)
							(end 0.1778 -0.2794)
						)
					)
					(width 0)
					(fill yes)
				)
			)
		)
		(pad "2" smd custom
			(at 0 0.4445 270)
			(size 0.1397 0.1397)
			(layers "F.Cu" "F.Mask" "F.Paste")
			(net "I2C_DRIVE_B_INS_SDA")
			(options
				(clearance outline)
				(anchor circle)
			)
			(primitives
				(gr_poly
					(pts
						(arc
							(start -0.1778 -0.2794)
							(mid -0.249642 -0.249642)
							(end -0.2794 -0.1778)
						)
						(arc
							(start -0.2794 0.1778)
							(mid -0.249642 0.249642)
							(end -0.1778 0.2794)
						)
						(arc
							(start 0.1778 0.2794)
							(mid 0.249642 0.249642)
							(end 0.2794 0.1778)
						)
						(arc
							(start 0.2794 -0.1778)
							(mid 0.249642 -0.249642)
							(end 0.1778 -0.2794)
						)
					)
					(width 0)
					(fill yes)
				)
			)
		)
	)
	(footprint ""
		(layer "F.Cu")
		(at 183.134 -366.649 90)
		(property "Reference" "R991"
			(at 0 0 90)
			(layer "F.SilkS")
			(hide yes)
			(effects
				(font
					(size 1.27 1.27)
				)
			)
		)
		(property "Value" "0R0603-PAD-2-GP-U"
			(at 2.1209 -0.1397 90)
			(unlocked yes)
			(layer "F.Fab")
			(hide yes)
			(effects
				(font
					(size 1.016 1.016)
					(thickness 0.1524)
				)
			)
		)
		(property "Device Type" "0R0603-PAD-1-U"
			(at 2.1209 -1.6637 90)
			(unlocked yes)
			(layer "F.Fab")
			(hide yes)
			(effects
				(font
					(size 1.016 1.016)
					(thickness 0.1524)
				)
			)
		)
		(duplicate_pad_numbers_are_jumpers no)
		(fp_rect
			(start -0.5842 1.3335)
			(end 0.5842 -1.3335)
			(stroke
				(width 0)
				(type default)
			)
			(fill no)
			(layer "F.CrtYd")
		)
		(fp_rect
			(start -0.5842 1.3335)
			(end 0.5842 -1.3335)
			(stroke
				(width 0)
				(type default)
			)
			(fill no)
			(layer "F.Fab")
		)
		(pad "1" smd custom
			(at 0 -0.762 90)
			(size 0.2159 0.2159)
			(layers "F.Cu" "F.Mask" "F.Paste")
			(net "AGND_CURRENT_MON")
			(options
				(clearance outline)
				(anchor circle)
			)
			(primitives
				(gr_poly
					(pts
						(arc
							(start -0.3302 -0.5842)
							(mid -0.402042 -0.554442)
							(end -0.4318 -0.4826)
						)
						(arc
							(start -0.4318 0.4826)
							(mid -0.402042 0.554442)
							(end -0.3302 0.5842)
						)
						(arc
							(start 0.3302 0.5842)
							(mid 0.402042 0.554442)
							(end 0.4318 0.4826)
						)
						(arc
							(start 0.4318 -0.4826)
							(mid 0.402042 -0.554442)
							(end 0.3302 -0.5842)
						)
					)
					(width 0)
					(fill yes)
				)
			)
		)
		(pad "2" smd custom
			(at 0 0.762 90)
			(size 0.2159 0.2159)
			(layers "F.Cu" "F.Mask" "F.Paste")
			(net "GND")
			(options
				(clearance outline)
				(anchor circle)
			)
			(primitives
				(gr_poly
					(pts
						(arc
							(start -0.4318 0.4826)
							(mid -0.402042 0.554442)
							(end -0.3302 0.5842)
						)
						(arc
							(start 0.3302 0.5842)
							(mid 0.402042 0.554442)
							(end 0.4318 0.4826)
						)
						(arc
							(start 0.4318 -0.4826)
							(mid 0.402042 -0.554442)
							(end 0.3302 -0.5842)
						)
						(arc
							(start -0.3302 -0.5842)
							(mid -0.402042 -0.554442)
							(end -0.4318 -0.4826)
						)
					)
					(width 0)
					(fill yes)
				)
			)
		)
	)
	(footprint ""
		(layer "F.Cu")
		(at 49.784 -214.249)
		(property "Reference" "R221"
			(at 0 0 0)
			(layer "F.SilkS")
			(hide yes)
			(effects
				(font
					(size 1.27 1.27)
				)
			)
		)
		(property "Value" "91R3F-1-GP"
			(at -0.0254 -2.5146 0)
			(unlocked yes)
			(layer "F.Fab")
			(hide yes)
			(effects
				(font
					(size 1.016 1.016)
					(thickness 0.1524)
				)
			)
		)
		(property "Device Type" "R603H22"
			(at -0.0254 -4.0386 0)
			(unlocked yes)
			(layer "F.Fab")
			(hide yes)
			(effects
				(font
					(size 1.016 1.016)
					(thickness 0.1524)
				)
			)
		)
		(duplicate_pad_numbers_are_jumpers no)
		(fp_line
			(start -0.4826 0)
			(end -0.2032 0)
			(stroke
				(width 0.2032)
				(type default)
			)
			(layer "F.SilkS")
		)
		(fp_line
			(start 0.2032 0)
			(end 0.4826 0)
			(stroke
				(width 0.2032)
				(type default)
			)
			(layer "F.SilkS")
		)
		(fp_rect
			(start -0.5842 1.3335)
			(end 0.5842 -1.3335)
			(stroke
				(width 0)
				(type default)
			)
			(fill no)
			(layer "F.CrtYd")
		)
		(fp_rect
			(start -0.5842 1.3335)
			(end 0.5842 -1.3335)
			(stroke
				(width 0)
				(type default)
			)
			(fill no)
			(layer "F.Fab")
		)
		(pad "1" smd custom
			(at 0 -0.762)
			(size 0.2159 0.2159)
			(layers "F.Cu" "F.Mask" "F.Paste")
			(net "P5V_B_1")
			(options
				(clearance outline)
				(anchor circle)
			)
			(primitives
				(gr_poly
					(pts
						(arc
							(start -0.3302 -0.4318)
							(mid -0.402042 -0.402042)
							(end -0.4318 -0.3302)
						)
						(arc
							(start -0.4318 0.3302)
							(mid -0.402042 0.402042)
							(end -0.3302 0.4318)
						)
						(arc
							(start 0.3302 0.4318)
							(mid 0.402042 0.402042)
							(end 0.4318 0.3302)
						)
						(arc
							(start 0.4318 -0.3302)
							(mid 0.402042 -0.402042)
							(end 0.3302 -0.4318)
						)
					)
					(width 0)
					(fill yes)
				)
			)
		)
		(pad "2" smd custom
			(at 0 0.762)
			(size 0.2159 0.2159)
			(layers "F.Cu" "F.Mask" "F.Paste")
			(net "DRV_ACT_1")
			(options
				(clearance outline)
				(anchor circle)
			)
			(primitives
				(gr_poly
					(pts
						(arc
							(start -0.3302 -0.4318)
							(mid -0.402042 -0.402042)
							(end -0.4318 -0.3302)
						)
						(arc
							(start -0.4318 0.3302)
							(mid -0.402042 0.402042)
							(end -0.3302 0.4318)
						)
						(arc
							(start 0.3302 0.4318)
							(mid 0.402042 0.402042)
							(end 0.4318 0.3302)
						)
						(arc
							(start 0.4318 -0.3302)
							(mid 0.402042 -0.402042)
							(end 0.3302 -0.4318)
						)
					)
					(width 0)
					(fill yes)
				)
			)
		)
	)
)
